(kicad_pcb
	(version 20241229)
	(generator "pcbnew")
	(generator_version "9.0")
	(general
		(thickness 1.62)
		(legacy_teardrops no)
	)
	(paper "A3")
	(title_block
		(title "COM Express 7 Baseboard")
		(date "2025-02-04")
		(rev "1.1.2")
		(company "Antmicro Ltd")
		(comment 1 "www.antmicro.com")
		(comment 9 "footprints 345-348 of 802")
	)
	(layers
		(0 "F.Cu" signal)
		(4 "In1.Cu" signal)
		(6 "In2.Cu" signal)
		(8 "In3.Cu" signal)
		(10 "In4.Cu" signal)
		(12 "In5.Cu" signal)
		(14 "In6.Cu" signal)
		(2 "B.Cu" signal)
		(9 "F.Adhes" user "F.Adhesive")
		(11 "B.Adhes" user "B.Adhesive")
		(13 "F.Paste" user)
		(15 "B.Paste" user)
		(5 "F.SilkS" user "F.Silkscreen")
		(7 "B.SilkS" user "B.Silkscreen")
		(1 "F.Mask" user)
		(3 "B.Mask" user)
		(17 "Dwgs.User" user "User.Drawings")
		(19 "Cmts.User" user "User.Comments")
		(21 "Eco1.User" user "User.Eco1")
		(23 "Eco2.User" user "User.Eco2")
		(25 "Edge.Cuts" user)
		(27 "Margin" user)
		(31 "F.CrtYd" user "F.Courtyard")
		(29 "B.CrtYd" user "B.Courtyard")
		(35 "F.Fab" user)
		(33 "B.Fab" user)
	)
	(footprint "antmicro-footprints:R_0201"
		(layer "F.Cu")
		(at 129.17 147.31 -90)
		(descr "Resistor SMD 0201")
		(tags "resistor SMD 0201")
		(property "Reference" "R306"
			(at 4.099 -0.58 270)
			(layer "F.SilkS")
			(effects
				(font
					(size 0.7 0.7)
					(thickness 0.15)
				)
				(justify left bottom)
			)
		)
		(property "Value" "R_0R_0201"
			(at 0 1.25 270)
			(layer "F.Fab")
			(effects
				(font
					(size 0.7 0.7)
					(thickness 0.15)
				)
				(justify left bottom)
			)
		)
		(property "Datasheet" "https://www.bourns.com/docs/product-datasheets/cr.pdf"
			(at 0 0 270)
			(layer "F.Fab")
			(hide yes)
			(effects
				(font
					(size 1.27 1.27)
					(thickness 0.15)
				)
			)
		)
		(property "Author" "Antmicro"
			(at -18.14 276.48 0)
			(layer "F.Fab")
			(hide yes)
			(effects
				(font
					(size 1 1)
					(thickness 0.15)
				)
			)
		)
		(property "License" "Apache-2.0"
			(at -18.14 276.48 0)
			(layer "F.Fab")
			(hide yes)
			(effects
				(font
					(size 1 1)
					(thickness 0.15)
				)
			)
		)
		(property "MPN" "CR0201-FX-0R00GLF"
			(at -18.14 276.48 0)
			(layer "F.Fab")
			(hide yes)
			(effects
				(font
					(size 1 1)
					(thickness 0.15)
				)
			)
		)
		(property "Manufacturer" "Bourns"
			(at -18.14 276.48 0)
			(layer "F.Fab")
			(hide yes)
			(effects
				(font
					(size 1 1)
					(thickness 0.15)
				)
			)
		)
		(property "Tolerance" "1%"
			(at -18.14 276.48 0)
			(layer "F.Fab")
			(hide yes)
			(effects
				(font
					(size 1 1)
					(thickness 0.15)
				)
			)
		)
		(property "Val" "0R"
			(at -18.14 276.48 0)
			(layer "F.Fab")
			(hide yes)
			(effects
				(font
					(size 1 1)
					(thickness 0.15)
				)
			)
		)
		(sheetname "KR to SFI #2")
		(sheetfile "kr_sfi.kicad_sch")
		(attr smd)
		(fp_rect
			(start -0.7 -0.35)
			(end 0.7 0.35)
			(stroke
				(width 0.05)
				(type default)
			)
			(fill no)
			(layer "F.CrtYd")
		)
		(fp_rect
			(start -0.3 -0.15)
			(end 0.298 0.148)
			(stroke
				(width 0.15)
				(type solid)
			)
			(fill no)
			(layer "F.Fab")
		)
		(pad "" smd roundrect
			(at -0.346 0 270)
			(size 0.318 0.36)
			(layers "F.Paste")
			(roundrect_rratio 0.25)
			(teardrops
				(best_length_ratio 0.2)
				(max_length 1)
				(best_width_ratio 0.9)
				(max_width 2)
				(curved_edges yes)
				(filter_ratio 0.9)
				(enabled yes)
				(allow_two_segments yes)
				(prefer_zone_connections yes)
			)
		)
		(pad "" smd roundrect
			(at 0.344 0 270)
			(size 0.318 0.36)
			(layers "F.Paste")
			(roundrect_rratio 0.25)
			(teardrops
				(best_length_ratio 0.2)
				(max_length 1)
				(best_width_ratio 0.9)
				(max_width 2)
				(curved_edges yes)
				(filter_ratio 0.9)
				(enabled yes)
				(allow_two_segments yes)
				(prefer_zone_connections yes)
			)
		)
		(pad "1" smd roundrect
			(at -0.32 0 270)
			(size 0.46 0.4)
			(layers "F.Cu" "F.Mask")
			(roundrect_rratio 0.25)
			(net 947 "/2xSFP+/KR to SFI #2/SFI_R.TX+")
			(pintype "passive")
			(teardrops
				(best_length_ratio 0.2)
				(max_length 1)
				(best_width_ratio 0.9)
				(max_width 2)
				(curved_edges yes)
				(filter_ratio 0.9)
				(enabled yes)
				(allow_two_segments yes)
				(prefer_zone_connections yes)
			)
		)
		(pad "2" smd roundrect
			(at 0.32 0 270)
			(size 0.46 0.4)
			(layers "F.Cu" "F.Mask")
			(roundrect_rratio 0.25)
			(net 879 "/2xSFP+/SFI1.TX+")
			(pintype "passive")
			(teardrops
				(best_length_ratio 0.2)
				(max_length 1)
				(best_width_ratio 0.9)
				(max_width 2)
				(curved_edges yes)
				(filter_ratio 0.9)
				(enabled yes)
				(allow_two_segments yes)
				(prefer_zone_connections yes)
			)
		)
	)
	(footprint "antmicro-footprints:C_0402_1005Metric"
		(layer "F.Cu")
		(at 120.4 146.301 90)
		(descr "Capacitor SMD 0402")
		(tags "capacitor SMD 0402")
		(property "Reference" "C128"
			(at 10.541 0.6 90)
			(layer "F.SilkS")
			(effects
				(font
					(size 0.7 0.7)
					(thickness 0.15)
				)
				(justify left bottom)
			)
		)
		(property "Value" "C_100n_0402"
			(at -1.022927 2.155213 90)
			(layer "F.Fab")
			(effects
				(font
					(size 0.7 0.7)
					(thickness 0.15)
				)
				(justify left bottom)
			)
		)
		(property "Datasheet" "https://www.murata.com/products/productdetail?partno=GRM155R61H104KE14%23"
			(at 0 0 90)
			(layer "F.Fab")
			(hide yes)
			(effects
				(font
					(size 1.27 1.27)
					(thickness 0.15)
				)
			)
		)
		(property "Author" "Antmicro"
			(at 266.701 25.901 0)
			(layer "F.Fab")
			(hide yes)
			(effects
				(font
					(size 1 1)
					(thickness 0.15)
				)
			)
		)
		(property "Dielectric" "X5R"
			(at 266.701 25.901 0)
			(layer "F.Fab")
			(hide yes)
			(effects
				(font
					(size 1 1)
					(thickness 0.15)
				)
			)
		)
		(property "License" "Apache-2.0"
			(at 266.701 25.901 0)
			(layer "F.Fab")
			(hide yes)
			(effects
				(font
					(size 1 1)
					(thickness 0.15)
				)
			)
		)
		(property "MPN" "GRM155R61H104KE14D"
			(at 266.701 25.901 0)
			(layer "F.Fab")
			(hide yes)
			(effects
				(font
					(size 1 1)
					(thickness 0.15)
				)
			)
		)
		(property "Manufacturer" "Murata"
			(at 266.701 25.901 0)
			(layer "F.Fab")
			(hide yes)
			(effects
				(font
					(size 1 1)
					(thickness 0.15)
				)
			)
		)
		(property "Public" "False"
			(at 266.701 25.901 0)
			(layer "F.Fab")
			(hide yes)
			(effects
				(font
					(size 1 1)
					(thickness 0.15)
				)
			)
		)
		(property "Val" "100n"
			(at 266.701 25.901 0)
			(layer "F.Fab")
			(hide yes)
			(effects
				(font
					(size 1 1)
					(thickness 0.15)
				)
			)
		)
		(property "Voltage" "50V"
			(at 266.701 25.901 0)
			(layer "F.Fab")
			(hide yes)
			(effects
				(font
					(size 1 1)
					(thickness 0.15)
				)
			)
		)
		(sheetname "PCIe redriver")
		(sheetfile "pcie_redriver.kicad_sch")
		(attr smd)
		(fp_rect
			(start -0.925 -0.47)
			(end 0.925 0.47)
			(stroke
				(width 0.05)
				(type default)
			)
			(fill no)
			(layer "F.CrtYd")
		)
		(fp_line
			(start 0.504 -0.25)
			(end 0.504 0.248)
			(stroke
				(width 0.15)
				(type solid)
			)
			(layer "F.Fab")
		)
		(fp_line
			(start -0.494 -0.25)
			(end 0.504 -0.25)
			(stroke
				(width 0.15)
				(type solid)
			)
			(layer "F.Fab")
		)
		(fp_line
			(start 0.504 0.248)
			(end -0.494 0.248)
			(stroke
				(width 0.15)
				(type solid)
			)
			(layer "F.Fab")
		)
		(fp_line
			(start -0.494 0.248)
			(end -0.494 -0.25)
			(stroke
				(width 0.15)
				(type solid)
			)
			(layer "F.Fab")
		)
		(pad "1" smd roundrect
			(at -0.48 0 90)
			(size 0.59 0.64)
			(layers "F.Cu" "F.Mask" "F.Paste")
			(roundrect_rratio 0.25)
			(net 1 "GND")
			(pintype "passive")
			(teardrops
				(best_length_ratio 0.2)
				(max_length 1)
				(best_width_ratio 0.9)
				(max_width 2)
				(curved_edges yes)
				(filter_ratio 0.9)
				(enabled yes)
				(allow_two_segments yes)
				(prefer_zone_connections yes)
			)
		)
		(pad "2" smd roundrect
			(at 0.48 0 90)
			(size 0.59 0.64)
			(layers "F.Cu" "F.Mask" "F.Paste")
			(roundrect_rratio 0.25)
			(net 2 "+3V3")
			(pintype "passive")
			(teardrops
				(best_length_ratio 0.2)
				(max_length 1)
				(best_width_ratio 0.9)
				(max_width 2)
				(curved_edges yes)
				(filter_ratio 0.9)
				(enabled yes)
				(allow_two_segments yes)
				(prefer_zone_connections yes)
			)
		)
	)
	(footprint "antmicro-footprints:R_0201"
		(layer "F.Cu")
		(at 147.33 147.31 -90)
		(descr "Resistor SMD 0201")
		(tags "resistor SMD 0201")
		(property "Reference" "R272"
			(at 4.125 -0.57 270)
			(layer "F.SilkS")
			(effects
				(font
					(size 0.7 0.7)
					(thickness 0.15)
				)
				(justify left bottom)
			)
		)
		(property "Value" "R_0R_0201"
			(at 0 1.25 270)
			(layer "F.Fab")
			(effects
				(font
					(size 0.7 0.7)
					(thickness 0.15)
				)
				(justify left bottom)
			)
		)
		(property "Datasheet" "https://www.bourns.com/docs/product-datasheets/cr.pdf"
			(at 0 0 270)
			(layer "F.Fab")
			(hide yes)
			(effects
				(font
					(size 1.27 1.27)
					(thickness 0.15)
				)
			)
		)
		(property "Author" "Antmicro"
			(at 0.02 294.64 0)
			(layer "F.Fab")
			(hide yes)
			(effects
				(font
					(size 1 1)
					(thickness 0.15)
				)
			)
		)
		(property "License" "Apache-2.0"
			(at 0.02 294.64 0)
			(layer "F.Fab")
			(hide yes)
			(effects
				(font
					(size 1 1)
					(thickness 0.15)
				)
			)
		)
		(property "MPN" "CR0201-FX-0R00GLF"
			(at 0.02 294.64 0)
			(layer "F.Fab")
			(hide yes)
			(effects
				(font
					(size 1 1)
					(thickness 0.15)
				)
			)
		)
		(property "Manufacturer" "Bourns"
			(at 0.02 294.64 0)
			(layer "F.Fab")
			(hide yes)
			(effects
				(font
					(size 1 1)
					(thickness 0.15)
				)
			)
		)
		(property "Tolerance" "1%"
			(at 0.02 294.64 0)
			(layer "F.Fab")
			(hide yes)
			(effects
				(font
					(size 1 1)
					(thickness 0.15)
				)
			)
		)
		(property "Val" "0R"
			(at 0.02 294.64 0)
			(layer "F.Fab")
			(hide yes)
			(effects
				(font
					(size 1 1)
					(thickness 0.15)
				)
			)
		)
		(sheetname "KR to SFI #1")
		(sheetfile "kr_sfi.kicad_sch")
		(attr smd)
		(fp_rect
			(start -0.7 -0.35)
			(end 0.7 0.35)
			(stroke
				(width 0.05)
				(type default)
			)
			(fill no)
			(layer "F.CrtYd")
		)
		(fp_rect
			(start -0.3 -0.15)
			(end 0.298 0.148)
			(stroke
				(width 0.15)
				(type solid)
			)
			(fill no)
			(layer "F.Fab")
		)
		(pad "" smd roundrect
			(at -0.346 0 270)
			(size 0.318 0.36)
			(layers "F.Paste")
			(roundrect_rratio 0.25)
			(teardrops
				(best_length_ratio 0.2)
				(max_length 1)
				(best_width_ratio 0.9)
				(max_width 2)
				(curved_edges yes)
				(filter_ratio 0.9)
				(enabled yes)
				(allow_two_segments yes)
				(prefer_zone_connections yes)
			)
		)
		(pad "" smd roundrect
			(at 0.344 0 270)
			(size 0.318 0.36)
			(layers "F.Paste")
			(roundrect_rratio 0.25)
			(teardrops
				(best_length_ratio 0.2)
				(max_length 1)
				(best_width_ratio 0.9)
				(max_width 2)
				(curved_edges yes)
				(filter_ratio 0.9)
				(enabled yes)
				(allow_two_segments yes)
				(prefer_zone_connections yes)
			)
		)
		(pad "1" smd roundrect
			(at -0.32 0 270)
			(size 0.46 0.4)
			(layers "F.Cu" "F.Mask")
			(roundrect_rratio 0.25)
			(net 666 "/2xSFP+/KR to SFI #1/SFI_R.TX+")
			(pintype "passive")
			(teardrops
				(best_length_ratio 0.2)
				(max_length 1)
				(best_width_ratio 0.9)
				(max_width 2)
				(curved_edges yes)
				(filter_ratio 0.9)
				(enabled yes)
				(allow_two_segments yes)
				(prefer_zone_connections yes)
			)
		)
		(pad "2" smd roundrect
			(at 0.32 0 270)
			(size 0.46 0.4)
			(layers "F.Cu" "F.Mask")
			(roundrect_rratio 0.25)
			(net 172 "/2xSFP+/SFI0.TX+")
			(pintype "passive")
			(teardrops
				(best_length_ratio 0.2)
				(max_length 1)
				(best_width_ratio 0.9)
				(max_width 2)
				(curved_edges yes)
				(filter_ratio 0.9)
				(enabled yes)
				(allow_two_segments yes)
				(prefer_zone_connections yes)
			)
		)
	)
	(footprint "antmicro-footprints:LED_0603_1608Metric_G"
		(layer "F.Cu")
		(at 283.36 75.7 -90)
		(descr "LED SMD 0603 Green")
		(tags "LED SMD 0603 Green")
		(property "Reference" "D14"
			(at -1.14 0.66 90)
			(layer "F.SilkS")
			(effects
				(font
					(size 0.7 0.7)
					(thickness 0.15)
				)
				(justify right bottom)
			)
		)
		(property "Value" "LED_G_0603_LTST-C190GKT"
			(at -0.001 1.599 90)
			(layer "F.Fab")
			(effects
				(font
					(size 0.7 0.7)
					(thickness 0.15)
				)
				(justify right bottom)
			)
		)
		(property "Datasheet" "https://media.digikey.com/pdf/Data%20Sheets/Lite-On%20PDFs/LTST-C190GKT.pdf"
			(at 0 0 270)
			(layer "F.Fab")
			(hide yes)
			(effects
				(font
					(size 1.27 1.27)
					(thickness 0.15)
				)
			)
		)
		(property "Author" "Antmicro"
			(at 207.66 359.06 0)
			(layer "F.Fab")
			(hide yes)
			(effects
				(font
					(size 1 1)
					(thickness 0.15)
				)
			)
		)
		(property "Color" "Green"
			(at 207.66 359.06 0)
			(layer "F.Fab")
			(hide yes)
			(effects
				(font
					(size 1 1)
					(thickness 0.15)
				)
			)
		)
		(property "License" "Apache-2.0"
			(at 207.66 359.06 0)
			(layer "F.Fab")
			(hide yes)
			(effects
				(font
					(size 1 1)
					(thickness 0.15)
				)
			)
		)
		(property "MPN" "LTST-C190GKT"
			(at 207.66 359.06 0)
			(layer "F.Fab")
			(hide yes)
			(effects
				(font
					(size 1 1)
					(thickness 0.15)
				)
			)
		)
		(property "Manufacturer" "Lite-On"
			(at 207.66 359.06 0)
			(layer "F.Fab")
			(hide yes)
			(effects
				(font
					(size 1 1)
					(thickness 0.15)
				)
			)
		)
		(property "Public" "False"
			(at 207.66 359.06 0)
			(layer "F.Fab")
			(hide yes)
			(effects
				(font
					(size 1 1)
					(thickness 0.15)
				)
			)
		)
		(sheetname "M.2 key M #2")
		(sheetfile "m2keym.kicad_sch")
		(attr smd)
		(fp_line
			(start 0.22 0.35)
			(end -0.22 0.35)
			(stroke
				(width 0.15)
				(type solid)
			)
			(layer "F.SilkS")
		)
		(fp_line
			(start -0.094672 0.201008)
			(end -0.094672 -0.198992)
			(stroke
				(width 0.1)
				(type solid)
			)
			(layer "F.SilkS")
		)
		(fp_line
			(start 0.105328 0.201008)
			(end -0.094672 0.001008)
			(stroke
				(width 0.1)
				(type solid)
			)
			(layer "F.SilkS")
		)
		(fp_line
			(start 0.105328 0.201008)
			(end 0.105328 -0.198992)
			(stroke
				(width 0.1)
				(type solid)
			)
			(layer "F.SilkS")
		)
		(fp_line
			(start -0.094672 0.001008)
			(end -0.24 0.001008)
			(stroke
				(width 0.1)
				(type solid)
			)
			(layer "F.SilkS")
		)
		(fp_line
			(start -0.094672 0.001008)
			(end 0.105328 -0.198992)
			(stroke
				(width 0.1)
				(type solid)
			)
			(layer "F.SilkS")
		)
		(fp_line
			(start 0.105328 0.001008)
			(end 0.24 0.001)
			(stroke
				(width 0.1)
				(type solid)
			)
			(layer "F.SilkS")
		)
		(fp_line
			(start -1.18 -0.319)
			(end -1.18 0.321)
			(stroke
				(width 0.15)
				(type solid)
			)
			(layer "F.SilkS")
		)
		(fp_line
			(start 0.22 -0.35)
			(end -0.22 -0.35)
			(stroke
				(width 0.15)
				(type solid)
			)
			(layer "F.SilkS")
		)
		(fp_rect
			(start 1.25 0.65)
			(end -1.25 -0.65)
			(stroke
				(width 0.05)
				(type solid)
			)
			(fill no)
			(layer "F.CrtYd")
		)
		(fp_line
			(start -0.199 0.2)
			(end -0.199 0.1)
			(stroke
				(width 0.15)
				(type solid)
			)
			(layer "F.Fab")
		)
		(fp_line
			(start 0.201 0.2)
			(end 0.201 0)
			(stroke
				(width 0.15)
				(type solid)
			)
			(layer "F.Fab")
		)
		(fp_line
			(start -0.199 0)
			(end -0.597 0)
			(stroke
				(width 0.15)
				(type solid)
			)
			(layer "F.Fab")
		)
		(fp_line
			(start -0.101 0)
			(end 0.201 0.2)
			(stroke
				(width 0.15)
				(type solid)
			)
			(layer "F.Fab")
		)
		(fp_line
			(start 0.201 0)
			(end 0.201 -0.202)
			(stroke
				(width 0.15)
				(type solid)
			)
			(layer "F.Fab")
		)
		(fp_line
			(start 0.599 0)
			(end 0.201 0)
			(stroke
				(width 0.15)
				(type solid)
			)
			(layer "F.Fab")
		)
		(fp_line
			(start -0.199 -0.202)
			(end -0.199 0.1)
			(stroke
				(width 0.15)
				(type solid)
			)
			(layer "F.Fab")
		)
		(fp_line
			(start 0.201 -0.202)
			(end -0.101 0)
			(stroke
				(width 0.15)
				(type solid)
			)
			(layer "F.Fab")
		)
		(fp_rect
			(start 0.848 0.4)
			(end -0.85 -0.402)
			(stroke
				(width 0.15)
				(type solid)
			)
			(fill no)
			(layer "F.Fab")
		)
		(pad "1" smd roundrect
			(at -0.7 0 90)
			(size 0.8 1)
			(layers "F.Cu" "F.Mask" "F.Paste")
			(roundrect_rratio 0.2)
			(net 936 "Net-(D14-C)")
			(pinfunction "C")
			(pintype "passive")
			(teardrops
				(best_length_ratio 0.2)
				(max_length 1)
				(best_width_ratio 0.9)
				(max_width 2)
				(curved_edges yes)
				(filter_ratio 0.9)
				(enabled yes)
				(allow_two_segments yes)
				(prefer_zone_connections yes)
			)
		)
		(pad "2" smd roundrect
			(at 0.7 0 90)
			(size 0.8 1)
			(layers "F.Cu" "F.Mask" "F.Paste")
			(roundrect_rratio 0.2)
			(net 892 "Net-(D14-A)")
			(pinfunction "A")
			(pintype "passive")
			(teardrops
				(best_length_ratio 0.2)
				(max_length 1)
				(best_width_ratio 0.9)
				(max_width 2)
				(curved_edges yes)
				(filter_ratio 0.9)
				(enabled yes)
				(allow_two_segments yes)
				(prefer_zone_connections yes)
			)
		)
	)
)
